(kicad_pcb
	(version 20260206)
	(generator "pcbnew")
	(generator_version "10.0")
	(general
		(thickness 1.6)
		(legacy_teardrops no)
	)
	(paper "A4")
	(title_block
		(title "01162023_DA0F0TEBIF0_F0T_Expander_BD_F_brd_V02_OCP.brd")
		(comment 1 "Grand Teton / footprints 3147-3153 of 9728")
	)
	(layers
		(0 "F.Cu" signal "TOP")
		(4 "In1.Cu" signal "GND")
		(6 "In2.Cu" signal "VCC")
		(8 "In3.Cu" signal "VCC1")
		(10 "In4.Cu" signal "GND1")
		(12 "In5.Cu" signal "IN1")
		(14 "In6.Cu" signal "GND2")
		(16 "In7.Cu" signal "IN2")
		(18 "In8.Cu" signal "GND3")
		(20 "In9.Cu" signal "IN3")
		(22 "In10.Cu" signal "GND4")
		(24 "In11.Cu" signal "IN4")
		(26 "In12.Cu" signal "GND5")
		(28 "In13.Cu" signal "IN5")
		(30 "In14.Cu" signal "GND6")
		(32 "In15.Cu" signal "IN6")
		(34 "In16.Cu" signal "GND7")
		(2 "B.Cu" signal "BOTTOM")
		(9 "F.Adhes" user "F.Adhesive")
		(11 "B.Adhes" user "B.Adhesive")
		(13 "F.Paste" user "Package Geometry/Pastemask Top")
		(15 "B.Paste" user "Package Geometry/Pastemask Bottom")
		(5 "F.SilkS" user "Ref Des/Silkscreen Top")
		(7 "B.SilkS" user "Ref Des/Silkscreen Bottom")
		(1 "F.Mask" user "Board Geometry/Soldermask Top")
		(3 "B.Mask" user "Board Geometry/Soldermask Bottom")
		(17 "Dwgs.User" user "User.Drawings")
		(19 "Cmts.User" user "User.Comments")
		(21 "Eco1.User" user "User.Eco1")
		(23 "Eco2.User" user "User.Eco2")
		(25 "Edge.Cuts" user "Board Geometry/Outline")
		(27 "Margin" user)
		(31 "F.CrtYd" user "Package Geometry/Place Bound Top")
		(29 "B.CrtYd" user "Package Geometry/Place Bound Bottom")
		(35 "F.Fab" user "Ref Des/Assembly Top")
		(33 "B.Fab" user "Ref Des/Assembly Bottom")
	)
	(footprint ""
		(layer "F.Cu")
		(at 110.321344 -177.469546 -90)
		(property "Reference" "PL3"
			(at 2.311146 -3.014726 90)
			(unlocked yes)
			(layer "F.SilkS")
			(effects
				(font
					(size 0.7874 0.5842)
					(thickness 0.1524)
				)
				(justify left)
			)
		)
		(property "Value" ""
			(at 0 0 270)
			(layer "F.Fab")
			(effects
				(font
					(size 1.27 1.27)
				)
			)
		)
		(duplicate_pad_numbers_are_jumpers no)
		(fp_line
			(start -2.249932 2.249932)
			(end -2.249932 1.3843)
			(stroke
				(width 0.1524)
				(type default)
			)
			(layer "F.SilkS")
		)
		(fp_line
			(start 2.249932 2.249932)
			(end -2.249932 2.249932)
			(stroke
				(width 0.1524)
				(type default)
			)
			(layer "F.SilkS")
		)
		(fp_line
			(start 2.249932 1.3843)
			(end 2.249932 2.249932)
			(stroke
				(width 0.1524)
				(type default)
			)
			(layer "F.SilkS")
		)
		(fp_line
			(start -2.249932 -1.3843)
			(end -2.249932 -2.249932)
			(stroke
				(width 0.1524)
				(type default)
			)
			(layer "F.SilkS")
		)
		(fp_line
			(start -2.249932 -2.249932)
			(end 2.249932 -2.249932)
			(stroke
				(width 0.1524)
				(type default)
			)
			(layer "F.SilkS")
		)
		(fp_line
			(start 2.249932 -2.249932)
			(end 2.249932 -1.3843)
			(stroke
				(width 0.1524)
				(type default)
			)
			(layer "F.SilkS")
		)
		(fp_line
			(start -2.249932 2.249932)
			(end -2.249932 -2.249932)
			(stroke
				(width 0.1)
				(type default)
			)
			(layer "F.Fab")
		)
		(fp_line
			(start 2.249932 2.249932)
			(end -2.249932 2.249932)
			(stroke
				(width 0.1)
				(type default)
			)
			(layer "F.Fab")
		)
		(fp_line
			(start -2.249932 -2.249932)
			(end 2.249932 -2.249932)
			(stroke
				(width 0.1)
				(type default)
			)
			(layer "F.Fab")
		)
		(fp_line
			(start 2.249932 -2.249932)
			(end 2.249932 2.249932)
			(stroke
				(width 0.1)
				(type default)
			)
			(layer "F.Fab")
		)
		(pad "1" smd rect
			(at -1.82499 0 270)
			(size 1.0668 2.5146)
			(layers "F.Cu" "F.Mask" "F.Paste")
			(net "P12V_AUX")
		)
		(pad "2" smd rect
			(at 1.82499 0 270)
			(size 1.0668 2.5146)
			(layers "F.Cu" "F.Mask" "F.Paste")
			(net "SW_P12V_P3V3_AUX_FLT")
		)
	)
	(footprint ""
		(layer "F.Cu")
		(at 358.405684 -285.088584 90)
		(property "Reference" "PC170"
			(at 0 0 90)
			(layer "F.SilkS")
			(hide yes)
			(effects
				(font
					(size 1.27 1.27)
				)
			)
		)
		(property "Value" ""
			(at 0 0 90)
			(layer "F.Fab")
			(effects
				(font
					(size 1.27 1.27)
				)
			)
		)
		(duplicate_pad_numbers_are_jumpers no)
		(fp_line
			(start 0.7874 -0.4064)
			(end 0.7874 0.4064)
			(stroke
				(width 0.1524)
				(type default)
			)
			(layer "F.SilkS")
		)
		(fp_line
			(start -0.7874 -0.4064)
			(end 0.7874 -0.4064)
			(stroke
				(width 0.1524)
				(type default)
			)
			(layer "F.SilkS")
		)
		(fp_line
			(start 0.7874 0.4064)
			(end -0.7874 0.4064)
			(stroke
				(width 0.1524)
				(type default)
			)
			(layer "F.SilkS")
		)
		(fp_line
			(start -0.7874 0.4064)
			(end -0.7874 -0.4064)
			(stroke
				(width 0.1524)
				(type default)
			)
			(layer "F.SilkS")
		)
		(fp_line
			(start -0.12065 -0.305054)
			(end -0.12065 -0.2794)
			(stroke
				(width 0.1)
				(type default)
			)
			(layer "F.Fab")
		)
		(fp_line
			(start -0.67945 -0.305054)
			(end -0.12065 -0.305054)
			(stroke
				(width 0.1)
				(type default)
			)
			(layer "F.Fab")
		)
		(fp_line
			(start 0.67945 -0.3048)
			(end 0.67945 0.3048)
			(stroke
				(width 0.1)
				(type default)
			)
			(layer "F.Fab")
		)
		(fp_line
			(start 0.12065 -0.3048)
			(end 0.67945 -0.3048)
			(stroke
				(width 0.1)
				(type default)
			)
			(layer "F.Fab")
		)
		(fp_line
			(start 0.12065 -0.2794)
			(end 0.12065 -0.3048)
			(stroke
				(width 0.1)
				(type default)
			)
			(layer "F.Fab")
		)
		(fp_line
			(start -0.12065 -0.2794)
			(end 0.12065 -0.2794)
			(stroke
				(width 0.1)
				(type default)
			)
			(layer "F.Fab")
		)
		(fp_line
			(start 0.120396 0.2794)
			(end -0.12065 0.2794)
			(stroke
				(width 0.1)
				(type default)
			)
			(layer "F.Fab")
		)
		(fp_line
			(start -0.12065 0.2794)
			(end -0.12065 0.3048)
			(stroke
				(width 0.1)
				(type default)
			)
			(layer "F.Fab")
		)
		(fp_line
			(start 0.67945 0.3048)
			(end 0.120396 0.3048)
			(stroke
				(width 0.1)
				(type default)
			)
			(layer "F.Fab")
		)
		(fp_line
			(start 0.120396 0.3048)
			(end 0.120396 0.2794)
			(stroke
				(width 0.1)
				(type default)
			)
			(layer "F.Fab")
		)
		(fp_line
			(start -0.12065 0.3048)
			(end -0.67945 0.3048)
			(stroke
				(width 0.1)
				(type default)
			)
			(layer "F.Fab")
		)
		(fp_line
			(start -0.67945 0.3048)
			(end -0.67945 -0.305054)
			(stroke
				(width 0.1)
				(type default)
			)
			(layer "F.Fab")
		)
		(pad "1" smd circle
			(at -0.40005 0 90)
			(size 0 0)
			(layers "F.Cu" "F.Mask" "F.Paste")
			(net "P0V8_PEX3_PVCC")
		)
		(pad "2" smd circle
			(at 0.40005 0 90)
			(size 0 0)
			(layers "F.Cu" "F.Mask" "F.Paste")
			(net "GND")
		)
	)
	(footprint ""
		(layer "F.Cu")
		(at 409.677108 -186.033918 180)
		(property "Reference" "R6426"
			(at 0 0 180)
			(layer "F.SilkS")
			(hide yes)
			(effects
				(font
					(size 1.27 1.27)
				)
			)
		)
		(property "Value" ""
			(at 0 0 180)
			(layer "F.Fab")
			(effects
				(font
					(size 1.27 1.27)
				)
			)
		)
		(duplicate_pad_numbers_are_jumpers no)
		(fp_line
			(start 0.7874 0.4064)
			(end -0.7874 0.4064)
			(stroke
				(width 0.1524)
				(type default)
			)
			(layer "F.SilkS")
		)
		(fp_line
			(start 0.7874 -0.4064)
			(end 0.7874 0.4064)
			(stroke
				(width 0.1524)
				(type default)
			)
			(layer "F.SilkS")
		)
		(fp_line
			(start -0.7874 0.4064)
			(end -0.7874 -0.4064)
			(stroke
				(width 0.1524)
				(type default)
			)
			(layer "F.SilkS")
		)
		(fp_line
			(start -0.7874 -0.4064)
			(end 0.7874 -0.4064)
			(stroke
				(width 0.1524)
				(type default)
			)
			(layer "F.SilkS")
		)
		(fp_line
			(start 0.67945 0.3048)
			(end 0.120396 0.3048)
			(stroke
				(width 0.1)
				(type default)
			)
			(layer "F.Fab")
		)
		(fp_line
			(start 0.67945 -0.3048)
			(end 0.67945 0.3048)
			(stroke
				(width 0.1)
				(type default)
			)
			(layer "F.Fab")
		)
		(fp_line
			(start 0.12065 -0.2794)
			(end 0.12065 -0.3048)
			(stroke
				(width 0.1)
				(type default)
			)
			(layer "F.Fab")
		)
		(fp_line
			(start 0.12065 -0.3048)
			(end 0.67945 -0.3048)
			(stroke
				(width 0.1)
				(type default)
			)
			(layer "F.Fab")
		)
		(fp_line
			(start 0.120396 0.3048)
			(end 0.120396 0.2794)
			(stroke
				(width 0.1)
				(type default)
			)
			(layer "F.Fab")
		)
		(fp_line
			(start 0.120396 0.2794)
			(end -0.12065 0.2794)
			(stroke
				(width 0.1)
				(type default)
			)
			(layer "F.Fab")
		)
		(fp_line
			(start -0.12065 0.3048)
			(end -0.67945 0.3048)
			(stroke
				(width 0.1)
				(type default)
			)
			(layer "F.Fab")
		)
		(fp_line
			(start -0.12065 0.2794)
			(end -0.12065 0.3048)
			(stroke
				(width 0.1)
				(type default)
			)
			(layer "F.Fab")
		)
		(fp_line
			(start -0.12065 -0.2794)
			(end 0.12065 -0.2794)
			(stroke
				(width 0.1)
				(type default)
			)
			(layer "F.Fab")
		)
		(fp_line
			(start -0.12065 -0.305054)
			(end -0.12065 -0.2794)
			(stroke
				(width 0.1)
				(type default)
			)
			(layer "F.Fab")
		)
		(fp_line
			(start -0.67945 0.3048)
			(end -0.67945 -0.305054)
			(stroke
				(width 0.1)
				(type default)
			)
			(layer "F.Fab")
		)
		(fp_line
			(start -0.67945 -0.305054)
			(end -0.12065 -0.305054)
			(stroke
				(width 0.1)
				(type default)
			)
			(layer "F.Fab")
		)
		(pad "1" smd circle
			(at -0.40005 0 180)
			(size 0 0)
			(layers "F.Cu" "F.Mask" "F.Paste")
			(net "FPGA_PEX0_MODE_SEL2_ISO")
		)
		(pad "2" smd circle
			(at 0.40005 0 180)
			(size 0 0)
			(layers "F.Cu" "F.Mask" "F.Paste")
			(net "PEX0_MODE_SEL2")
		)
	)
	(footprint ""
		(layer "F.Cu")
		(at 312.21934 -119.584724 180)
		(property "Reference" "C453"
			(at 0 0 180)
			(layer "F.SilkS")
			(hide yes)
			(effects
				(font
					(size 1.27 1.27)
				)
			)
		)
		(property "Value" ""
			(at 0 0 180)
			(layer "F.Fab")
			(effects
				(font
					(size 1.27 1.27)
				)
			)
		)
		(duplicate_pad_numbers_are_jumpers no)
		(fp_line
			(start 0.299974 0.150114)
			(end -0.299974 0.150114)
			(stroke
				(width 0.1)
				(type default)
			)
			(layer "F.Fab")
		)
		(fp_line
			(start 0.299974 -0.150114)
			(end 0.299974 0.150114)
			(stroke
				(width 0.1)
				(type default)
			)
			(layer "F.Fab")
		)
		(fp_line
			(start -0.299974 0.150114)
			(end -0.299974 -0.150114)
			(stroke
				(width 0.1)
				(type default)
			)
			(layer "F.Fab")
		)
		(fp_line
			(start -0.299974 -0.150114)
			(end 0.299974 -0.150114)
			(stroke
				(width 0.1)
				(type default)
			)
			(layer "F.Fab")
		)
		(pad "1" smd rect
			(at -0.2667 0 180)
			(size 0.3048 0.381)
			(layers "F.Cu" "F.Mask" "F.Paste")
			(net "P5E_PEX2_STN0_TX_DP<0>")
		)
		(pad "2" smd rect
			(at 0.2667 0 180)
			(size 0.3048 0.381)
			(layers "F.Cu" "F.Mask" "F.Paste")
			(net "P5E_PEX2_STN0_TX_C_DP<0>")
		)
	)
	(footprint ""
		(layer "F.Cu")
		(at 144.149318 -284.195012 -90)
		(property "Reference" "C3190"
			(at 0 0 270)
			(layer "F.SilkS")
			(hide yes)
			(effects
				(font
					(size 1.27 1.27)
				)
			)
		)
		(property "Value" ""
			(at 0 0 270)
			(layer "F.Fab")
			(effects
				(font
					(size 1.27 1.27)
				)
			)
		)
		(duplicate_pad_numbers_are_jumpers no)
		(fp_line
			(start -0.299974 0.150114)
			(end -0.299974 -0.150114)
			(stroke
				(width 0.1)
				(type default)
			)
			(layer "F.Fab")
		)
		(fp_line
			(start 0.299974 0.150114)
			(end -0.299974 0.150114)
			(stroke
				(width 0.1)
				(type default)
			)
			(layer "F.Fab")
		)
		(fp_line
			(start -0.299974 -0.150114)
			(end 0.299974 -0.150114)
			(stroke
				(width 0.1)
				(type default)
			)
			(layer "F.Fab")
		)
		(fp_line
			(start 0.299974 -0.150114)
			(end 0.299974 0.150114)
			(stroke
				(width 0.1)
				(type default)
			)
			(layer "F.Fab")
		)
		(pad "1" smd rect
			(at -0.2667 0 270)
			(size 0.3048 0.381)
			(layers "F.Cu" "F.Mask" "F.Paste")
			(net "P1V8_PLL0_PEX1")
		)
		(pad "2" smd rect
			(at 0.2667 0 270)
			(size 0.3048 0.381)
			(layers "F.Cu" "F.Mask" "F.Paste")
			(net "GND")
		)
	)
	(footprint ""
		(layer "F.Cu")
		(at 243.3828 -213.3854 90)
		(property "Reference" "R6591"
			(at 0 0 90)
			(layer "F.SilkS")
			(hide yes)
			(effects
				(font
					(size 1.27 1.27)
				)
			)
		)
		(property "Value" ""
			(at 0 0 90)
			(layer "F.Fab")
			(effects
				(font
					(size 1.27 1.27)
				)
			)
		)
		(duplicate_pad_numbers_are_jumpers no)
		(fp_line
			(start 0.7874 -0.4064)
			(end 0.7874 0.4064)
			(stroke
				(width 0.1524)
				(type default)
			)
			(layer "F.SilkS")
		)
		(fp_line
			(start -0.7874 -0.4064)
			(end 0.7874 -0.4064)
			(stroke
				(width 0.1524)
				(type default)
			)
			(layer "F.SilkS")
		)
		(fp_line
			(start 0.7874 0.4064)
			(end -0.7874 0.4064)
			(stroke
				(width 0.1524)
				(type default)
			)
			(layer "F.SilkS")
		)
		(fp_line
			(start -0.7874 0.4064)
			(end -0.7874 -0.4064)
			(stroke
				(width 0.1524)
				(type default)
			)
			(layer "F.SilkS")
		)
		(fp_line
			(start -0.12065 -0.305054)
			(end -0.12065 -0.2794)
			(stroke
				(width 0.1)
				(type default)
			)
			(layer "F.Fab")
		)
		(fp_line
			(start -0.67945 -0.305054)
			(end -0.12065 -0.305054)
			(stroke
				(width 0.1)
				(type default)
			)
			(layer "F.Fab")
		)
		(fp_line
			(start 0.67945 -0.3048)
			(end 0.67945 0.3048)
			(stroke
				(width 0.1)
				(type default)
			)
			(layer "F.Fab")
		)
		(fp_line
			(start 0.12065 -0.3048)
			(end 0.67945 -0.3048)
			(stroke
				(width 0.1)
				(type default)
			)
			(layer "F.Fab")
		)
		(fp_line
			(start 0.12065 -0.2794)
			(end 0.12065 -0.3048)
			(stroke
				(width 0.1)
				(type default)
			)
			(layer "F.Fab")
		)
		(fp_line
			(start -0.12065 -0.2794)
			(end 0.12065 -0.2794)
			(stroke
				(width 0.1)
				(type default)
			)
			(layer "F.Fab")
		)
		(fp_line
			(start 0.120396 0.2794)
			(end -0.12065 0.2794)
			(stroke
				(width 0.1)
				(type default)
			)
			(layer "F.Fab")
		)
		(fp_line
			(start -0.12065 0.2794)
			(end -0.12065 0.3048)
			(stroke
				(width 0.1)
				(type default)
			)
			(layer "F.Fab")
		)
		(fp_line
			(start 0.67945 0.3048)
			(end 0.120396 0.3048)
			(stroke
				(width 0.1)
				(type default)
			)
			(layer "F.Fab")
		)
		(fp_line
			(start 0.120396 0.3048)
			(end 0.120396 0.2794)
			(stroke
				(width 0.1)
				(type default)
			)
			(layer "F.Fab")
		)
		(fp_line
			(start -0.12065 0.3048)
			(end -0.67945 0.3048)
			(stroke
				(width 0.1)
				(type default)
			)
			(layer "F.Fab")
		)
		(fp_line
			(start -0.67945 0.3048)
			(end -0.67945 -0.305054)
			(stroke
				(width 0.1)
				(type default)
			)
			(layer "F.Fab")
		)
		(pad "1" smd circle
			(at -0.40005 0 90)
			(size 0 0)
			(layers "F.Cu" "F.Mask" "F.Paste")
			(net "P1V8_PLL0_PEX1")
		)
		(pad "2" smd circle
			(at 0.40005 0 90)
			(size 0 0)
			(layers "F.Cu" "F.Mask" "F.Paste")
			(net "P1V8_PLL0_PEX1_SCALED")
		)
	)
	(footprint ""
		(layer "F.Cu")
		(at 121.854468 -48.21809)
		(property "Reference" "PD61"
			(at -3.490468 2.24536 0)
			(unlocked yes)
			(layer "F.SilkS")
			(effects
				(font
					(size 0.7874 0.5842)
					(thickness 0.1524)
				)
				(justify left)
			)
		)
		(property "Value" ""
			(at 0 0 0)
			(layer "F.Fab")
			(effects
				(font
					(size 1.27 1.27)
				)
			)
		)
		(duplicate_pad_numbers_are_jumpers no)
		(fp_line
			(start -3.400044 -1.459992)
			(end 4.107942 -1.459992)
			(stroke
				(width 0.1524)
				(type default)
			)
			(layer "F.SilkS")
		)
		(fp_line
			(start -3.400044 1.459992)
			(end -3.400044 -1.459992)
			(stroke
				(width 0.1524)
				(type default)
			)
			(layer "F.SilkS")
		)
		(fp_line
			(start 4.107942 -1.459992)
			(end 4.107942 1.459992)
			(stroke
				(width 0.1524)
				(type default)
			)
			(layer "F.SilkS")
		)
		(fp_line
			(start 4.107942 1.459992)
			(end -3.400044 1.459992)
			(stroke
				(width 0.1524)
				(type default)
			)
			(layer "F.SilkS")
		)
		(fp_poly
			(pts
				(xy 4.107942 -1.459992) (xy 4.107942 1.459992) (xy 3.308096 1.459992) (xy 3.308096 -1.459992)
			)
			(stroke
				(width 0)
				(type default)
			)
			(fill yes)
			(layer "F.SilkS")
		)
		(fp_line
			(start -2.29997 -1.459992)
			(end 2.29997 -1.459992)
			(stroke
				(width 0.1)
				(type default)
			)
			(layer "F.Fab")
		)
		(fp_line
			(start -2.29997 1.459992)
			(end -2.29997 -1.459992)
			(stroke
				(width 0.1)
				(type default)
			)
			(layer "F.Fab")
		)
		(fp_line
			(start 2.29997 -1.459992)
			(end 2.29997 1.459992)
			(stroke
				(width 0.1)
				(type default)
			)
			(layer "F.Fab")
		)
		(fp_line
			(start 2.29997 1.459992)
			(end -2.29997 1.459992)
			(stroke
				(width 0.1)
				(type default)
			)
			(layer "F.Fab")
		)
		(fp_text user "+"
			(at -4.7752 -0.12065 0)
			(unlocked yes)
			(layer "F.SilkS")
			(effects
				(font
					(size 1.905 1.4224)
					(thickness 0.1524)
				)
				(justify left)
			)
		)
		(fp_text user "-"
			(at 5.4102 0.29845 180)
			(unlocked yes)
			(layer "F.SilkS")
			(effects
				(font
					(size 1.905 1.4224)
					(thickness 0.1524)
				)
				(justify left)
			)
		)
		(fp_text user "+"
			(at -4.7752 -0.12065 0)
			(unlocked yes)
			(layer "F.Fab")
			(effects
				(font
					(size 1.905 1.4224)
					(thickness 0.1524)
				)
				(justify left)
			)
		)
		(fp_text user "-"
			(at 5.4102 0.29845 180)
			(unlocked yes)
			(layer "F.Fab")
			(effects
				(font
					(size 1.905 1.4224)
					(thickness 0.1524)
				)
				(justify left)
			)
		)
		(pad "A" smd rect
			(at -1.999996 0 90)
			(size 1.7018 2.5146)
			(layers "F.Cu" "F.Mask" "F.Paste")
			(net "GND")
		)
		(pad "C" smd rect
			(at 1.999996 0 90)
			(size 1.7018 2.5146)
			(layers "F.Cu" "F.Mask" "F.Paste")
			(net "P3V3_SSD4")
		)
	)
)
